(kicad_pcb
	(version 20260206)
	(generator "pcbnew")
	(generator_version "10.0")
	(general
		(thickness 1.6)
		(legacy_teardrops no)
	)
	(paper "A4")
	(title_block
		(title "peb — Lightning_PEB_BRD.brd")
		(comment 1 "Lightning (Wiwynn / Facebook NVMe JBOF) / footprints 1775-1782 of 2563")
	)
	(layers
		(0 "F.Cu" signal "TOP")
		(4 "In1.Cu" signal "L2GND")
		(6 "In2.Cu" signal "L3")
		(8 "In3.Cu" signal "L4VCC")
		(10 "In4.Cu" signal "L5VCC")
		(12 "In5.Cu" signal "L6")
		(14 "In6.Cu" signal "L7GND")
		(2 "B.Cu" signal "BOTTOM")
		(9 "F.Adhes" user "F.Adhesive")
		(11 "B.Adhes" user "B.Adhesive")
		(13 "F.Paste" user "Package Geometry/Pastemask Top")
		(15 "B.Paste" user "Package Geometry/Pastemask Bottom")
		(5 "F.SilkS" user "Ref Des/Silkscreen Top")
		(7 "B.SilkS" user "Ref Des/Silkscreen Bottom")
		(1 "F.Mask" user "Board Geometry/Soldermask Top")
		(3 "B.Mask" user "Board Geometry/Soldermask Bottom")
		(17 "Dwgs.User" user "User.Drawings")
		(19 "Cmts.User" user "User.Comments")
		(21 "Eco1.User" user "User.Eco1")
		(23 "Eco2.User" user "User.Eco2")
		(25 "Edge.Cuts" user "Board Geometry/Outline")
		(27 "Margin" user)
		(31 "F.CrtYd" user "Package Geometry/Place Bound Top")
		(29 "B.CrtYd" user "Package Geometry/Place Bound Bottom")
		(35 "F.Fab" user "Ref Des/Assembly Top")
		(33 "B.Fab" user "Ref Des/Assembly Bottom")
	)
	(footprint ""
		(layer "B.Cu")
		(at 180.72354 -3.09372 180)
		(property "Reference" "R213"
			(at 0 0 0)
			(layer "B.SilkS")
			(hide yes)
			(effects
				(font
					(size 1.27 1.27)
				)
				(justify mirror)
			)
		)
		(property "Value" "4K7R2F-GP"
			(at -0.064008 -3.993896 180)
			(unlocked yes)
			(layer "B.Fab")
			(hide yes)
			(effects
				(font
					(size 1.016 1.016)
					(thickness 0.1524)
				)
				(justify mirror)
			)
		)
		(property "Device Type" "R402H16"
			(at -0.064008 -5.517896 180)
			(unlocked yes)
			(layer "B.Fab")
			(hide yes)
			(effects
				(font
					(size 1.016 1.016)
					(thickness 0.1524)
				)
				(justify mirror)
			)
		)
		(duplicate_pad_numbers_are_jumpers no)
		(fp_line
			(start 0.508 -0.9398)
			(end 0.508 0.9398)
			(stroke
				(width 0.1524)
				(type default)
			)
			(layer "B.SilkS")
		)
		(fp_line
			(start -0.508 -0.9398)
			(end 0.508 -0.9398)
			(stroke
				(width 0.1524)
				(type default)
			)
			(layer "B.SilkS")
		)
		(fp_rect
			(start 0.508 0.9398)
			(end -0.508 -0.9398)
			(stroke
				(width 0)
				(type default)
			)
			(fill no)
			(layer "B.CrtYd")
		)
		(fp_rect
			(start 0.508 0.9398)
			(end -0.508 -0.9398)
			(stroke
				(width 0)
				(type default)
			)
			(fill no)
			(layer "B.Fab")
		)
		(pad "1" smd custom
			(at 0 -0.4445)
			(size 0.1397 0.1397)
			(layers "B.Cu" "B.Mask" "B.Paste")
			(net "P3V3_STBY")
			(options
				(clearance outline)
				(anchor circle)
			)
			(primitives
				(gr_poly
					(pts
						(arc
							(start -0.1778 0.2794)
							(mid -0.249642 0.249642)
							(end -0.2794 0.1778)
						)
						(arc
							(start -0.2794 -0.1778)
							(mid -0.249642 -0.249642)
							(end -0.1778 -0.2794)
						)
						(arc
							(start 0.1778 -0.2794)
							(mid 0.249642 -0.249642)
							(end 0.2794 -0.1778)
						)
						(arc
							(start 0.2794 0.1778)
							(mid 0.249642 0.249642)
							(end 0.1778 0.2794)
						)
					)
					(width 0)
					(fill yes)
				)
			)
		)
		(pad "2" smd custom
			(at 0 0.4445)
			(size 0.1397 0.1397)
			(layers "B.Cu" "B.Mask" "B.Paste")
			(net "CLK_P_1_R")
			(options
				(clearance outline)
				(anchor circle)
			)
			(primitives
				(gr_poly
					(pts
						(arc
							(start -0.1778 0.2794)
							(mid -0.249642 0.249642)
							(end -0.2794 0.1778)
						)
						(arc
							(start -0.2794 -0.1778)
							(mid -0.249642 -0.249642)
							(end -0.1778 -0.2794)
						)
						(arc
							(start 0.1778 -0.2794)
							(mid 0.249642 -0.249642)
							(end 0.2794 -0.1778)
						)
						(arc
							(start 0.2794 0.1778)
							(mid 0.249642 0.249642)
							(end 0.1778 0.2794)
						)
					)
					(width 0)
					(fill yes)
				)
			)
		)
	)
	(footprint ""
		(layer "B.Cu")
		(at 231.5972 -36.0045 90)
		(property "Reference" "TP205"
			(at 0 0 90)
			(layer "B.SilkS")
			(hide yes)
			(effects
				(font
					(size 1.27 1.27)
				)
				(justify mirror)
			)
		)
		(property "Value" "TPAD28-2-GP"
			(at 0.0127 -1.6637 90)
			(unlocked yes)
			(layer "B.Fab")
			(hide yes)
			(effects
				(font
					(size 1.016 1.016)
					(thickness 0.1524)
				)
				(justify mirror)
			)
		)
		(property "Device Type" "TPAD28"
			(at 0.0127 -3.1877 90)
			(unlocked yes)
			(layer "B.Fab")
			(hide yes)
			(effects
				(font
					(size 1.016 1.016)
					(thickness 0.1524)
				)
				(justify mirror)
			)
		)
		(duplicate_pad_numbers_are_jumpers no)
		(fp_poly
			(pts
				(arc
					(start 0 0.3556)
					(mid 0 -0.3556)
					(end 0 0.3556)
				)
			)
			(stroke
				(width 0)
				(type default)
			)
			(fill no)
			(layer "B.CrtYd")
		)
		(fp_poly
			(pts
				(arc
					(start 0 0.6096)
					(mid 0 -0.6096)
					(end 0 0.6096)
				)
			)
			(stroke
				(width 0)
				(type default)
			)
			(fill no)
			(layer "B.Fab")
		)
		(pad "1" smd circle
			(at 0 0 270)
			(size 0.7112 0.7112)
			(layers "B.Cu" "B.Mask" "B.Paste")
			(net "RMII_RX_ER")
		)
	)
	(footprint ""
		(layer "B.Cu")
		(at 235.6104 -36.5252 180)
		(property "Reference" "R9"
			(at 0 0 0)
			(layer "B.SilkS")
			(hide yes)
			(effects
				(font
					(size 1.27 1.27)
				)
				(justify mirror)
			)
		)
		(property "Value" "33R1J-GP"
			(at 3.3274 -1.3335 180)
			(unlocked yes)
			(layer "B.Fab")
			(hide yes)
			(effects
				(font
					(size 1.016 1.016)
					(thickness 0.1524)
				)
				(justify mirror)
			)
		)
		(property "Device Type" "R0201H12"
			(at 3.3274 -2.8575 180)
			(unlocked yes)
			(layer "B.Fab")
			(hide yes)
			(effects
				(font
					(size 1.016 1.016)
					(thickness 0.1524)
				)
				(justify mirror)
			)
		)
		(duplicate_pad_numbers_are_jumpers no)
		(fp_rect
			(start 0.2794 0.6477)
			(end -0.2794 -0.6477)
			(stroke
				(width 0)
				(type default)
			)
			(fill no)
			(layer "B.CrtYd")
		)
		(fp_rect
			(start 0.2794 0.6477)
			(end -0.2794 -0.6477)
			(stroke
				(width 0)
				(type default)
			)
			(fill no)
			(layer "B.Fab")
		)
		(pad "1" smd custom
			(at 0 -0.2794)
			(size 0.0762 0.0762)
			(layers "B.Cu" "B.Mask" "B.Paste")
			(net "PCIE_REFCLK_H3_N")
			(options
				(clearance outline)
				(anchor circle)
			)
			(primitives
				(gr_poly
					(pts
						(arc
							(start 0.1524 0.127)
							(mid 0.137521 0.162921)
							(end 0.1016 0.1778)
						)
						(arc
							(start -0.1016 0.1778)
							(mid -0.137521 0.162921)
							(end -0.1524 0.127)
						)
						(arc
							(start -0.1524 -0.127)
							(mid -0.137521 -0.162921)
							(end -0.1016 -0.1778)
						)
						(arc
							(start 0.1016 -0.1778)
							(mid 0.137521 -0.162921)
							(end 0.1524 -0.127)
						)
					)
					(width 0)
					(fill yes)
				)
			)
		)
		(pad "2" smd custom
			(at 0 0.2794)
			(size 0.0762 0.0762)
			(layers "B.Cu" "B.Mask" "B.Paste")
			(net "PCIE_REFCLK_H3_P")
			(options
				(clearance outline)
				(anchor circle)
			)
			(primitives
				(gr_poly
					(pts
						(arc
							(start 0.1524 0.127)
							(mid 0.137521 0.162921)
							(end 0.1016 0.1778)
						)
						(arc
							(start -0.1016 0.1778)
							(mid -0.137521 0.162921)
							(end -0.1524 0.127)
						)
						(arc
							(start -0.1524 -0.127)
							(mid -0.137521 -0.162921)
							(end -0.1016 -0.1778)
						)
						(arc
							(start 0.1016 -0.1778)
							(mid 0.137521 -0.162921)
							(end 0.1524 -0.127)
						)
					)
					(width 0)
					(fill yes)
				)
			)
		)
	)
	(footprint ""
		(layer "B.Cu")
		(at 235.1024 -41.995852 -90)
		(property "Reference" "C436"
			(at 0 0 90)
			(layer "B.SilkS")
			(hide yes)
			(effects
				(font
					(size 1.27 1.27)
				)
				(justify mirror)
			)
		)
		(property "Value" "SCD1U16V1KX-1-GP"
			(at 2.8321 -1.7399 270)
			(unlocked yes)
			(layer "B.Fab")
			(hide yes)
			(effects
				(font
					(size 1.016 1.016)
					(thickness 0.1524)
				)
				(justify mirror)
			)
		)
		(property "Device Type" "C0201H13"
			(at 2.8321 -3.2639 270)
			(unlocked yes)
			(layer "B.Fab")
			(hide yes)
			(effects
				(font
					(size 1.016 1.016)
					(thickness 0.1524)
				)
				(justify mirror)
			)
		)
		(duplicate_pad_numbers_are_jumpers no)
		(fp_rect
			(start 0.2794 0.6477)
			(end -0.2794 -0.6477)
			(stroke
				(width 0)
				(type default)
			)
			(fill no)
			(layer "B.CrtYd")
		)
		(fp_rect
			(start 0.2794 0.6477)
			(end -0.2794 -0.6477)
			(stroke
				(width 0)
				(type default)
			)
			(fill no)
			(layer "B.Fab")
		)
		(pad "1" smd custom
			(at 0 -0.2794 90)
			(size 0.0762 0.0762)
			(layers "B.Cu" "B.Mask" "B.Paste")
			(net "DUT_VDD")
			(options
				(clearance outline)
				(anchor circle)
			)
			(primitives
				(gr_poly
					(pts
						(arc
							(start 0.1524 0.127)
							(mid 0.137521 0.162921)
							(end 0.1016 0.1778)
						)
						(arc
							(start -0.1016 0.1778)
							(mid -0.137521 0.162921)
							(end -0.1524 0.127)
						)
						(arc
							(start -0.1524 -0.127)
							(mid -0.137521 -0.162921)
							(end -0.1016 -0.1778)
						)
						(arc
							(start 0.1016 -0.1778)
							(mid 0.137521 -0.162921)
							(end 0.1524 -0.127)
						)
					)
					(width 0)
					(fill yes)
				)
			)
		)
		(pad "2" smd custom
			(at 0 0.2794 90)
			(size 0.0762 0.0762)
			(layers "B.Cu" "B.Mask" "B.Paste")
			(net "GND")
			(options
				(clearance outline)
				(anchor circle)
			)
			(primitives
				(gr_poly
					(pts
						(arc
							(start 0.1524 0.127)
							(mid 0.137521 0.162921)
							(end 0.1016 0.1778)
						)
						(arc
							(start -0.1016 0.1778)
							(mid -0.137521 0.162921)
							(end -0.1524 0.127)
						)
						(arc
							(start -0.1524 -0.127)
							(mid -0.137521 -0.162921)
							(end -0.1016 -0.1778)
						)
						(arc
							(start 0.1016 -0.1778)
							(mid 0.137521 -0.162921)
							(end 0.1524 -0.127)
						)
					)
					(width 0)
					(fill yes)
				)
			)
		)
	)
	(footprint ""
		(layer "B.Cu")
		(at 182.1307 -4.55168 90)
		(property "Reference" "R205"
			(at 0 0 90)
			(layer "B.SilkS")
			(hide yes)
			(effects
				(font
					(size 1.27 1.27)
				)
				(justify mirror)
			)
		)
		(property "Value" "4K7R2F-GP"
			(at -0.064008 -3.993896 90)
			(unlocked yes)
			(layer "B.Fab")
			(hide yes)
			(effects
				(font
					(size 1.016 1.016)
					(thickness 0.1524)
				)
				(justify mirror)
			)
		)
		(property "Device Type" "R402H16"
			(at -0.064008 -5.517896 90)
			(unlocked yes)
			(layer "B.Fab")
			(hide yes)
			(effects
				(font
					(size 1.016 1.016)
					(thickness 0.1524)
				)
				(justify mirror)
			)
		)
		(duplicate_pad_numbers_are_jumpers no)
		(fp_line
			(start 0.508 -0.9398)
			(end 0.508 0.9398)
			(stroke
				(width 0.1524)
				(type default)
			)
			(layer "B.SilkS")
		)
		(fp_line
			(start -0.508 -0.9398)
			(end 0.508 -0.9398)
			(stroke
				(width 0.1524)
				(type default)
			)
			(layer "B.SilkS")
		)
		(fp_rect
			(start 0.508 0.9398)
			(end -0.508 -0.9398)
			(stroke
				(width 0)
				(type default)
			)
			(fill no)
			(layer "B.CrtYd")
		)
		(fp_rect
			(start 0.508 0.9398)
			(end -0.508 -0.9398)
			(stroke
				(width 0)
				(type default)
			)
			(fill no)
			(layer "B.Fab")
		)
		(pad "1" smd custom
			(at 0 -0.4445 270)
			(size 0.1397 0.1397)
			(layers "B.Cu" "B.Mask" "B.Paste")
			(net "CLK_P_1_R")
			(options
				(clearance outline)
				(anchor circle)
			)
			(primitives
				(gr_poly
					(pts
						(arc
							(start -0.1778 0.2794)
							(mid -0.249642 0.249642)
							(end -0.2794 0.1778)
						)
						(arc
							(start -0.2794 -0.1778)
							(mid -0.249642 -0.249642)
							(end -0.1778 -0.2794)
						)
						(arc
							(start 0.1778 -0.2794)
							(mid 0.249642 -0.249642)
							(end 0.2794 -0.1778)
						)
						(arc
							(start 0.2794 0.1778)
							(mid 0.249642 0.249642)
							(end 0.1778 0.2794)
						)
					)
					(width 0)
					(fill yes)
				)
			)
		)
		(pad "2" smd custom
			(at 0 0.4445 270)
			(size 0.1397 0.1397)
			(layers "B.Cu" "B.Mask" "B.Paste")
			(net "GND")
			(options
				(clearance outline)
				(anchor circle)
			)
			(primitives
				(gr_poly
					(pts
						(arc
							(start -0.1778 0.2794)
							(mid -0.249642 0.249642)
							(end -0.2794 0.1778)
						)
						(arc
							(start -0.2794 -0.1778)
							(mid -0.249642 -0.249642)
							(end -0.1778 -0.2794)
						)
						(arc
							(start 0.1778 -0.2794)
							(mid 0.249642 -0.249642)
							(end 0.2794 -0.1778)
						)
						(arc
							(start 0.2794 0.1778)
							(mid 0.249642 0.249642)
							(end 0.1778 0.2794)
						)
					)
					(width 0)
					(fill yes)
				)
			)
		)
	)
	(footprint ""
		(layer "B.Cu")
		(at 70.715124 -183.235092 180)
		(property "Reference" "R518"
			(at 0 0 0)
			(layer "B.SilkS")
			(hide yes)
			(effects
				(font
					(size 1.27 1.27)
				)
				(justify mirror)
			)
		)
		(property "Value" "10KR2F-2-GP"
			(at -0.064008 -3.993896 180)
			(unlocked yes)
			(layer "B.Fab")
			(hide yes)
			(effects
				(font
					(size 1.016 1.016)
					(thickness 0.1524)
				)
				(justify mirror)
			)
		)
		(property "Device Type" "R402H16"
			(at -0.064008 -5.517896 180)
			(unlocked yes)
			(layer "B.Fab")
			(hide yes)
			(effects
				(font
					(size 1.016 1.016)
					(thickness 0.1524)
				)
				(justify mirror)
			)
		)
		(duplicate_pad_numbers_are_jumpers no)
		(fp_line
			(start 0.508 -0.9398)
			(end 0.508 0.9398)
			(stroke
				(width 0.1524)
				(type default)
			)
			(layer "B.SilkS")
		)
		(fp_line
			(start -0.508 -0.9398)
			(end 0.508 -0.9398)
			(stroke
				(width 0.1524)
				(type default)
			)
			(layer "B.SilkS")
		)
		(fp_rect
			(start 0.508 0.9398)
			(end -0.508 -0.9398)
			(stroke
				(width 0)
				(type default)
			)
			(fill no)
			(layer "B.CrtYd")
		)
		(fp_rect
			(start 0.508 0.9398)
			(end -0.508 -0.9398)
			(stroke
				(width 0)
				(type default)
			)
			(fill no)
			(layer "B.Fab")
		)
		(pad "1" smd custom
			(at 0 -0.4445)
			(size 0.1397 0.1397)
			(layers "B.Cu" "B.Mask" "B.Paste")
			(net "P3V3_STBY")
			(options
				(clearance outline)
				(anchor circle)
			)
			(primitives
				(gr_poly
					(pts
						(arc
							(start -0.1778 0.2794)
							(mid -0.249642 0.249642)
							(end -0.2794 0.1778)
						)
						(arc
							(start -0.2794 -0.1778)
							(mid -0.249642 -0.249642)
							(end -0.1778 -0.2794)
						)
						(arc
							(start 0.1778 -0.2794)
							(mid 0.249642 -0.249642)
							(end 0.2794 -0.1778)
						)
						(arc
							(start 0.2794 0.1778)
							(mid 0.249642 0.249642)
							(end 0.1778 0.2794)
						)
					)
					(width 0)
					(fill yes)
				)
			)
		)
		(pad "2" smd custom
			(at 0 0.4445)
			(size 0.1397 0.1397)
			(layers "B.Cu" "B.Mask" "B.Paste")
			(net "IOEXP1_AD2")
			(options
				(clearance outline)
				(anchor circle)
			)
			(primitives
				(gr_poly
					(pts
						(arc
							(start -0.1778 0.2794)
							(mid -0.249642 0.249642)
							(end -0.2794 0.1778)
						)
						(arc
							(start -0.2794 -0.1778)
							(mid -0.249642 -0.249642)
							(end -0.1778 -0.2794)
						)
						(arc
							(start 0.1778 -0.2794)
							(mid 0.249642 -0.249642)
							(end 0.2794 -0.1778)
						)
						(arc
							(start 0.2794 0.1778)
							(mid 0.249642 0.249642)
							(end 0.1778 0.2794)
						)
					)
					(width 0)
					(fill yes)
				)
			)
		)
	)
	(footprint ""
		(layer "B.Cu")
		(at 249.428 -26.67 -90)
		(property "Reference" "TP286"
			(at 0 0 90)
			(layer "B.SilkS")
			(hide yes)
			(effects
				(font
					(size 1.27 1.27)
				)
				(justify mirror)
			)
		)
		(property "Value" "TPAD28-2-GP"
			(at 0.0127 -1.6637 270)
			(unlocked yes)
			(layer "B.Fab")
			(hide yes)
			(effects
				(font
					(size 1.016 1.016)
					(thickness 0.1524)
				)
				(justify mirror)
			)
		)
		(property "Device Type" "TPAD28"
			(at 0.0127 -3.1877 270)
			(unlocked yes)
			(layer "B.Fab")
			(hide yes)
			(effects
				(font
					(size 1.016 1.016)
					(thickness 0.1524)
				)
				(justify mirror)
			)
		)
		(duplicate_pad_numbers_are_jumpers no)
		(fp_poly
			(pts
				(arc
					(start 0 -0.3556)
					(mid 0 0.3556)
					(end 0 -0.3556)
				)
			)
			(stroke
				(width 0)
				(type default)
			)
			(fill no)
			(layer "B.CrtYd")
		)
		(fp_poly
			(pts
				(arc
					(start 0 -0.6096)
					(mid 0 0.6096)
					(end 0 -0.6096)
				)
			)
			(stroke
				(width 0)
				(type default)
			)
			(fill no)
			(layer "B.Fab")
		)
		(pad "1" smd circle
			(at 0 0 90)
			(size 0.7112 0.7112)
			(layers "B.Cu" "B.Mask" "B.Paste")
			(net "TWI_SCL5")
		)
	)
	(footprint ""
		(layer "B.Cu")
		(at 252.603 -40.9956 -90)
		(property "Reference" "C616"
			(at 0 0 90)
			(layer "B.SilkS")
			(hide yes)
			(effects
				(font
					(size 1.27 1.27)
				)
				(justify mirror)
			)
		)
		(property "Value" "SCD1U16V1KX-1-GP"
			(at 2.8321 -1.7399 270)
			(unlocked yes)
			(layer "B.Fab")
			(hide yes)
			(effects
				(font
					(size 1.016 1.016)
					(thickness 0.1524)
				)
				(justify mirror)
			)
		)
		(property "Device Type" "C0201H13"
			(at 2.8321 -3.2639 270)
			(unlocked yes)
			(layer "B.Fab")
			(hide yes)
			(effects
				(font
					(size 1.016 1.016)
					(thickness 0.1524)
				)
				(justify mirror)
			)
		)
		(duplicate_pad_numbers_are_jumpers no)
		(fp_rect
			(start 0.2794 0.6477)
			(end -0.2794 -0.6477)
			(stroke
				(width 0)
				(type default)
			)
			(fill no)
			(layer "B.CrtYd")
		)
		(fp_rect
			(start 0.2794 0.6477)
			(end -0.2794 -0.6477)
			(stroke
				(width 0)
				(type default)
			)
			(fill no)
			(layer "B.Fab")
		)
		(pad "1" smd custom
			(at 0 -0.2794 90)
			(size 0.0762 0.0762)
			(layers "B.Cu" "B.Mask" "B.Paste")
			(net "DUT_AVD_PCIE")
			(options
				(clearance outline)
				(anchor circle)
			)
			(primitives
				(gr_poly
					(pts
						(arc
							(start 0.1524 0.127)
							(mid 0.137521 0.162921)
							(end 0.1016 0.1778)
						)
						(arc
							(start -0.1016 0.1778)
							(mid -0.137521 0.162921)
							(end -0.1524 0.127)
						)
						(arc
							(start -0.1524 -0.127)
							(mid -0.137521 -0.162921)
							(end -0.1016 -0.1778)
						)
						(arc
							(start 0.1016 -0.1778)
							(mid 0.137521 -0.162921)
							(end 0.1524 -0.127)
						)
					)
					(width 0)
					(fill yes)
				)
			)
		)
		(pad "2" smd custom
			(at 0 0.2794 90)
			(size 0.0762 0.0762)
			(layers "B.Cu" "B.Mask" "B.Paste")
			(net "GND")
			(options
				(clearance outline)
				(anchor circle)
			)
			(primitives
				(gr_poly
					(pts
						(arc
							(start 0.1524 0.127)
							(mid 0.137521 0.162921)
							(end 0.1016 0.1778)
						)
						(arc
							(start -0.1016 0.1778)
							(mid -0.137521 0.162921)
							(end -0.1524 0.127)
						)
						(arc
							(start -0.1524 -0.127)
							(mid -0.137521 -0.162921)
							(end -0.1016 -0.1778)
						)
						(arc
							(start 0.1016 -0.1778)
							(mid 0.137521 -0.162921)
							(end 0.1524 -0.127)
						)
					)
					(width 0)
					(fill yes)
				)
			)
		)
	)
)
